(kicad_pcb
	(version 20260206)
	(generator "pcbnew")
	(generator_version "10.0")
	(general
		(thickness 1.6)
		(legacy_teardrops no)
	)
	(paper "A4")
	(title_block
		(title "pdpb — Lightning_PDPB_BRD.brd")
		(comment 1 "Lightning (Wiwynn / Facebook NVMe JBOF) / footprints 967-973 of 1140")
	)
	(layers
		(0 "F.Cu" signal "TOP")
		(4 "In1.Cu" signal "L2GND")
		(6 "In2.Cu" signal "L3")
		(8 "In3.Cu" signal "L4VCC")
		(10 "In4.Cu" signal "L5VCC")
		(12 "In5.Cu" signal "L6")
		(14 "In6.Cu" signal "L7GND")
		(2 "B.Cu" signal "BOTTOM")
		(9 "F.Adhes" user "F.Adhesive")
		(11 "B.Adhes" user "B.Adhesive")
		(13 "F.Paste" user "Package Geometry/Pastemask Top")
		(15 "B.Paste" user "Package Geometry/Pastemask Bottom")
		(5 "F.SilkS" user "Ref Des/Silkscreen Top")
		(7 "B.SilkS" user "Ref Des/Silkscreen Bottom")
		(1 "F.Mask" user "Board Geometry/Soldermask Top")
		(3 "B.Mask" user "Board Geometry/Soldermask Bottom")
		(17 "Dwgs.User" user "User.Drawings")
		(19 "Cmts.User" user "User.Comments")
		(21 "Eco1.User" user "User.Eco1")
		(23 "Eco2.User" user "User.Eco2")
		(25 "Edge.Cuts" user "Board Geometry/Outline")
		(27 "Margin" user)
		(31 "F.CrtYd" user "Package Geometry/Place Bound Top")
		(29 "B.CrtYd" user "Package Geometry/Place Bound Bottom")
		(35 "F.Fab" user "Ref Des/Assembly Top")
		(33 "B.Fab" user "Ref Des/Assembly Bottom")
	)
	(footprint ""
		(layer "F.Cu")
		(at 89.535 -18.669)
		(property "Reference" "R381"
			(at 0 0 0)
			(layer "F.SilkS")
			(hide yes)
			(effects
				(font
					(size 1.27 1.27)
				)
			)
		)
		(property "Value" "4K7R2J-2-GP"
			(at 0.064008 -3.993896 0)
			(unlocked yes)
			(layer "F.Fab")
			(hide yes)
			(effects
				(font
					(size 1.016 1.016)
					(thickness 0.1524)
				)
			)
		)
		(property "Device Type" "R402H16"
			(at 0.064008 -5.517896 0)
			(unlocked yes)
			(layer "F.Fab")
			(hide yes)
			(effects
				(font
					(size 1.016 1.016)
					(thickness 0.1524)
				)
			)
		)
		(duplicate_pad_numbers_are_jumpers no)
		(fp_line
			(start -0.508 -0.9398)
			(end -0.508 0.9398)
			(stroke
				(width 0.1524)
				(type default)
			)
			(layer "F.SilkS")
		)
		(fp_line
			(start 0.508 -0.9398)
			(end -0.508 -0.9398)
			(stroke
				(width 0.1524)
				(type default)
			)
			(layer "F.SilkS")
		)
		(fp_rect
			(start -0.508 0.9398)
			(end 0.508 -0.9398)
			(stroke
				(width 0)
				(type default)
			)
			(fill no)
			(layer "F.CrtYd")
		)
		(fp_rect
			(start -0.508 0.9398)
			(end 0.508 -0.9398)
			(stroke
				(width 0)
				(type default)
			)
			(fill no)
			(layer "F.Fab")
		)
		(pad "1" smd custom
			(at 0 -0.4445)
			(size 0.1397 0.1397)
			(layers "F.Cu" "F.Mask" "F.Paste")
			(net "VOL_SEN_ADDR")
			(options
				(clearance outline)
				(anchor circle)
			)
			(primitives
				(gr_poly
					(pts
						(arc
							(start -0.1778 -0.2794)
							(mid -0.249642 -0.249642)
							(end -0.2794 -0.1778)
						)
						(arc
							(start -0.2794 0.1778)
							(mid -0.249642 0.249642)
							(end -0.1778 0.2794)
						)
						(arc
							(start 0.1778 0.2794)
							(mid 0.249642 0.249642)
							(end 0.2794 0.1778)
						)
						(arc
							(start 0.2794 -0.1778)
							(mid 0.249642 -0.249642)
							(end 0.1778 -0.2794)
						)
					)
					(width 0)
					(fill yes)
				)
			)
		)
		(pad "2" smd custom
			(at 0 0.4445)
			(size 0.1397 0.1397)
			(layers "F.Cu" "F.Mask" "F.Paste")
			(net "GND")
			(options
				(clearance outline)
				(anchor circle)
			)
			(primitives
				(gr_poly
					(pts
						(arc
							(start -0.1778 -0.2794)
							(mid -0.249642 -0.249642)
							(end -0.2794 -0.1778)
						)
						(arc
							(start -0.2794 0.1778)
							(mid -0.249642 0.249642)
							(end -0.1778 0.2794)
						)
						(arc
							(start 0.1778 0.2794)
							(mid 0.249642 0.249642)
							(end 0.2794 0.1778)
						)
						(arc
							(start 0.2794 -0.1778)
							(mid 0.249642 -0.249642)
							(end 0.1778 -0.2794)
						)
					)
					(width 0)
					(fill yes)
				)
			)
		)
	)
	(footprint ""
		(layer "F.Cu")
		(at 82.931 -309.499 90)
		(property "Reference" "SR950"
			(at 0 0 90)
			(layer "F.SilkS")
			(hide yes)
			(effects
				(font
					(size 1.27 1.27)
				)
			)
		)
		(property "Value" "4K7R2F-GP"
			(at 0.064008 -3.993896 90)
			(unlocked yes)
			(layer "F.Fab")
			(hide yes)
			(effects
				(font
					(size 1.016 1.016)
					(thickness 0.1524)
				)
			)
		)
		(property "Device Type" "R402H16"
			(at 0.064008 -5.517896 90)
			(unlocked yes)
			(layer "F.Fab")
			(hide yes)
			(effects
				(font
					(size 1.016 1.016)
					(thickness 0.1524)
				)
			)
		)
		(duplicate_pad_numbers_are_jumpers no)
		(fp_line
			(start 0.508 -0.9398)
			(end -0.508 -0.9398)
			(stroke
				(width 0.1524)
				(type default)
			)
			(layer "F.SilkS")
		)
		(fp_line
			(start -0.508 -0.9398)
			(end -0.508 0.9398)
			(stroke
				(width 0.1524)
				(type default)
			)
			(layer "F.SilkS")
		)
		(fp_rect
			(start -0.508 0.9398)
			(end 0.508 -0.9398)
			(stroke
				(width 0)
				(type default)
			)
			(fill no)
			(layer "F.CrtYd")
		)
		(fp_rect
			(start -0.508 0.9398)
			(end 0.508 -0.9398)
			(stroke
				(width 0)
				(type default)
			)
			(fill no)
			(layer "F.Fab")
		)
		(pad "1" smd custom
			(at 0 -0.4445 90)
			(size 0.1397 0.1397)
			(layers "F.Cu" "F.Mask" "F.Paste")
			(net "VDD_DIFF_2")
			(options
				(clearance outline)
				(anchor circle)
			)
			(primitives
				(gr_poly
					(pts
						(arc
							(start -0.1778 -0.2794)
							(mid -0.249642 -0.249642)
							(end -0.2794 -0.1778)
						)
						(arc
							(start -0.2794 0.1778)
							(mid -0.249642 0.249642)
							(end -0.1778 0.2794)
						)
						(arc
							(start 0.1778 0.2794)
							(mid 0.249642 0.249642)
							(end 0.2794 0.1778)
						)
						(arc
							(start 0.2794 -0.1778)
							(mid 0.249642 -0.249642)
							(end 0.1778 -0.2794)
						)
					)
					(width 0)
					(fill yes)
				)
			)
		)
		(pad "2" smd custom
			(at 0 0.4445 90)
			(size 0.1397 0.1397)
			(layers "F.Cu" "F.Mask" "F.Paste")
			(net "CLK_BUF_EU2_HIBW_BYPM_LOBW#")
			(options
				(clearance outline)
				(anchor circle)
			)
			(primitives
				(gr_poly
					(pts
						(arc
							(start -0.1778 -0.2794)
							(mid -0.249642 -0.249642)
							(end -0.2794 -0.1778)
						)
						(arc
							(start -0.2794 0.1778)
							(mid -0.249642 0.249642)
							(end -0.1778 0.2794)
						)
						(arc
							(start 0.1778 0.2794)
							(mid 0.249642 0.249642)
							(end 0.2794 0.1778)
						)
						(arc
							(start 0.2794 -0.1778)
							(mid 0.249642 -0.249642)
							(end 0.1778 -0.2794)
						)
					)
					(width 0)
					(fill yes)
				)
			)
		)
	)
	(footprint ""
		(layer "F.Cu")
		(at 29.845 -218.44 90)
		(property "Reference" "R413"
			(at 0 0 90)
			(layer "F.SilkS")
			(hide yes)
			(effects
				(font
					(size 1.27 1.27)
				)
			)
		)
		(property "Value" "0R2J-2-GP"
			(at 0.064008 -3.993896 90)
			(unlocked yes)
			(layer "F.Fab")
			(hide yes)
			(effects
				(font
					(size 1.016 1.016)
					(thickness 0.1524)
				)
			)
		)
		(property "Device Type" "R402H16"
			(at 0.064008 -5.517896 90)
			(unlocked yes)
			(layer "F.Fab")
			(hide yes)
			(effects
				(font
					(size 1.016 1.016)
					(thickness 0.1524)
				)
			)
		)
		(duplicate_pad_numbers_are_jumpers no)
		(fp_line
			(start 0.508 -0.9398)
			(end -0.508 -0.9398)
			(stroke
				(width 0.1524)
				(type default)
			)
			(layer "F.SilkS")
		)
		(fp_line
			(start -0.508 -0.9398)
			(end -0.508 0.9398)
			(stroke
				(width 0.1524)
				(type default)
			)
			(layer "F.SilkS")
		)
		(fp_rect
			(start -0.508 0.9398)
			(end 0.508 -0.9398)
			(stroke
				(width 0)
				(type default)
			)
			(fill no)
			(layer "F.CrtYd")
		)
		(fp_rect
			(start -0.508 0.9398)
			(end 0.508 -0.9398)
			(stroke
				(width 0)
				(type default)
			)
			(fill no)
			(layer "F.Fab")
		)
		(pad "1" smd custom
			(at 0 -0.4445 90)
			(size 0.1397 0.1397)
			(layers "F.Cu" "F.Mask" "F.Paste")
			(net "SCL_DR12_R")
			(options
				(clearance outline)
				(anchor circle)
			)
			(primitives
				(gr_poly
					(pts
						(arc
							(start -0.1778 -0.2794)
							(mid -0.249642 -0.249642)
							(end -0.2794 -0.1778)
						)
						(arc
							(start -0.2794 0.1778)
							(mid -0.249642 0.249642)
							(end -0.1778 0.2794)
						)
						(arc
							(start 0.1778 0.2794)
							(mid 0.249642 0.249642)
							(end 0.2794 0.1778)
						)
						(arc
							(start 0.2794 -0.1778)
							(mid 0.249642 -0.249642)
							(end 0.1778 -0.2794)
						)
					)
					(width 0)
					(fill yes)
				)
			)
		)
		(pad "2" smd custom
			(at 0 0.4445 90)
			(size 0.1397 0.1397)
			(layers "F.Cu" "F.Mask" "F.Paste")
			(net "SCL_DR12")
			(options
				(clearance outline)
				(anchor circle)
			)
			(primitives
				(gr_poly
					(pts
						(arc
							(start -0.1778 -0.2794)
							(mid -0.249642 -0.249642)
							(end -0.2794 -0.1778)
						)
						(arc
							(start -0.2794 0.1778)
							(mid -0.249642 0.249642)
							(end -0.1778 0.2794)
						)
						(arc
							(start 0.1778 0.2794)
							(mid 0.249642 0.249642)
							(end 0.2794 0.1778)
						)
						(arc
							(start 0.2794 -0.1778)
							(mid 0.249642 -0.249642)
							(end 0.1778 -0.2794)
						)
					)
					(width 0)
					(fill yes)
				)
			)
		)
	)
	(footprint ""
		(layer "F.Cu")
		(at 42.650918 -243.84 90)
		(property "Reference" "R9831"
			(at 0 0 90)
			(layer "F.SilkS")
			(hide yes)
			(effects
				(font
					(size 1.27 1.27)
				)
			)
		)
		(property "Value" "0R2J-2-GP"
			(at 0.064008 -3.993896 90)
			(unlocked yes)
			(layer "F.Fab")
			(hide yes)
			(effects
				(font
					(size 1.016 1.016)
					(thickness 0.1524)
				)
			)
		)
		(property "Device Type" "R402H16"
			(at 0.064008 -5.517896 90)
			(unlocked yes)
			(layer "F.Fab")
			(hide yes)
			(effects
				(font
					(size 1.016 1.016)
					(thickness 0.1524)
				)
			)
		)
		(duplicate_pad_numbers_are_jumpers no)
		(fp_line
			(start 0.508 -0.9398)
			(end -0.508 -0.9398)
			(stroke
				(width 0.1524)
				(type default)
			)
			(layer "F.SilkS")
		)
		(fp_line
			(start -0.508 -0.9398)
			(end -0.508 0.9398)
			(stroke
				(width 0.1524)
				(type default)
			)
			(layer "F.SilkS")
		)
		(fp_rect
			(start -0.508 0.9398)
			(end 0.508 -0.9398)
			(stroke
				(width 0)
				(type default)
			)
			(fill no)
			(layer "F.CrtYd")
		)
		(fp_rect
			(start -0.508 0.9398)
			(end 0.508 -0.9398)
			(stroke
				(width 0)
				(type default)
			)
			(fill no)
			(layer "F.Fab")
		)
		(pad "1" smd custom
			(at 0 -0.4445 90)
			(size 0.1397 0.1397)
			(layers "F.Cu" "F.Mask" "F.Paste")
			(net "SSD_ACT_DR7_R")
			(options
				(clearance outline)
				(anchor circle)
			)
			(primitives
				(gr_poly
					(pts
						(arc
							(start -0.1778 -0.2794)
							(mid -0.249642 -0.249642)
							(end -0.2794 -0.1778)
						)
						(arc
							(start -0.2794 0.1778)
							(mid -0.249642 0.249642)
							(end -0.1778 0.2794)
						)
						(arc
							(start 0.1778 0.2794)
							(mid 0.249642 0.249642)
							(end 0.2794 0.1778)
						)
						(arc
							(start 0.2794 -0.1778)
							(mid 0.249642 -0.249642)
							(end 0.1778 -0.2794)
						)
					)
					(width 0)
					(fill yes)
				)
			)
		)
		(pad "2" smd custom
			(at 0 0.4445 90)
			(size 0.1397 0.1397)
			(layers "F.Cu" "F.Mask" "F.Paste")
			(net "SSD_ACT_DR7")
			(options
				(clearance outline)
				(anchor circle)
			)
			(primitives
				(gr_poly
					(pts
						(arc
							(start -0.1778 -0.2794)
							(mid -0.249642 -0.249642)
							(end -0.2794 -0.1778)
						)
						(arc
							(start -0.2794 0.1778)
							(mid -0.249642 0.249642)
							(end -0.1778 0.2794)
						)
						(arc
							(start 0.1778 0.2794)
							(mid 0.249642 0.249642)
							(end 0.2794 0.1778)
						)
						(arc
							(start 0.2794 -0.1778)
							(mid 0.249642 -0.249642)
							(end 0.1778 -0.2794)
						)
					)
					(width 0)
					(fill yes)
				)
			)
		)
	)
	(footprint ""
		(layer "F.Cu")
		(at 224.663 -438.658)
		(property "Reference" "PR9091"
			(at 0 0 0)
			(layer "F.SilkS")
			(hide yes)
			(effects
				(font
					(size 1.27 1.27)
				)
			)
		)
		(property "Value" "3D01R5F-GP"
			(at 0 -8.9535 0)
			(unlocked yes)
			(layer "F.Fab")
			(hide yes)
			(effects
				(font
					(size 1.27 1.016)
					(thickness 0.1524)
				)
			)
		)
		(property "Device Type" "R805H24"
			(at 0 -10.6299 0)
			(unlocked yes)
			(layer "F.Fab")
			(hide yes)
			(effects
				(font
					(size 1.27 1.016)
					(thickness 0.1524)
				)
			)
		)
		(duplicate_pad_numbers_are_jumpers no)
		(fp_line
			(start -0.889 -1.7018)
			(end -0.889 0.2794)
			(stroke
				(width 0.1524)
				(type default)
			)
			(layer "F.SilkS")
		)
		(fp_line
			(start -0.889 0.0762)
			(end -0.889 1.7018)
			(stroke
				(width 0.1524)
				(type default)
			)
			(layer "F.SilkS")
		)
		(fp_line
			(start -0.889 1.7018)
			(end 0.889 1.7018)
			(stroke
				(width 0.1524)
				(type default)
			)
			(layer "F.SilkS")
		)
		(fp_line
			(start 0.889 -1.7018)
			(end -0.889 -1.7018)
			(stroke
				(width 0.1524)
				(type default)
			)
			(layer "F.SilkS")
		)
		(fp_line
			(start 0.889 -1.7018)
			(end 0.889 -0.381)
			(stroke
				(width 0.1524)
				(type default)
			)
			(layer "F.SilkS")
		)
		(fp_line
			(start 0.889 1.7018)
			(end 0.889 -0.508)
			(stroke
				(width 0.1524)
				(type default)
			)
			(layer "F.SilkS")
		)
		(fp_poly
			(pts
				(xy 0.9652 -1.778) (xy 0.9652 1.778) (xy -0.9652 1.778) (xy -0.9652 -1.778)
			)
			(stroke
				(width 0)
				(type default)
			)
			(fill no)
			(layer "F.CrtYd")
		)
		(fp_rect
			(start -0.9652 1.778)
			(end 0.9652 -1.778)
			(stroke
				(width 0)
				(type default)
			)
			(fill no)
			(layer "F.Fab")
		)
		(pad "1" smd rect
			(at 0 -0.9652)
			(size 1.397 1.143)
			(layers "F.Cu" "F.Mask" "F.Paste")
			(net "P3V3_SNB")
		)
		(pad "2" smd rect
			(at 0 0.9652)
			(size 1.397 1.143)
			(layers "F.Cu" "F.Mask" "F.Paste")
			(net "GND")
		)
	)
	(footprint ""
		(layer "F.Cu")
		(at 228.499924 -41.099994)
		(property "Reference" "LED4"
			(at 0 0 0)
			(layer "F.SilkS")
			(hide yes)
			(effects
				(font
					(size 1.27 1.27)
				)
			)
		)
		(property "Value" "LED-RB-4-GP"
			(at 5.88899 1.80848 0)
			(unlocked yes)
			(layer "F.Fab")
			(hide yes)
			(effects
				(font
					(size 1.016 1.016)
					(thickness 0.1524)
				)
			)
		)
		(property "Device Type" "LED1613-4PH20"
			(at 5.88899 0.28448 0)
			(unlocked yes)
			(layer "F.Fab")
			(hide yes)
			(effects
				(font
					(size 1.016 1.016)
					(thickness 0.1524)
				)
			)
		)
		(duplicate_pad_numbers_are_jumpers no)
		(fp_line
			(start -1.4478 -0.9652)
			(end 1.4478 -0.9652)
			(stroke
				(width 0.1524)
				(type default)
			)
			(layer "F.SilkS")
		)
		(fp_line
			(start -1.4478 0.9652)
			(end -1.4478 -0.9652)
			(stroke
				(width 0.1524)
				(type default)
			)
			(layer "F.SilkS")
		)
		(fp_line
			(start -1.4478 0.9652)
			(end -1.4478 -0.9652)
			(stroke
				(width 0.508)
				(type default)
			)
			(layer "F.SilkS")
		)
		(fp_line
			(start 1.4478 -0.9652)
			(end 1.4478 0.9652)
			(stroke
				(width 0.1524)
				(type default)
			)
			(layer "F.SilkS")
		)
		(fp_line
			(start 1.4478 0.9652)
			(end -1.4478 0.9652)
			(stroke
				(width 0.1524)
				(type default)
			)
			(layer "F.SilkS")
		)
		(fp_rect
			(start -0.8001 0.6477)
			(end 0.8001 -0.6477)
			(stroke
				(width 0)
				(type default)
			)
			(fill no)
			(layer "F.CrtYd")
		)
		(fp_poly
			(pts
				(xy -1.7018 1.2192) (xy -1.7018 -0.06223) (xy -0.8001 -0.06223) (xy -0.8001 0.6477) (xy 0.8001 0.6477)
				(xy 0.8001 -0.6477) (xy -0.8001 -0.6477) (xy -0.8001 -0.0635) (xy -1.7018 -0.0635) (xy -1.7018 -1.2192)
				(xy 1.7018 -1.2192) (xy 1.7018 1.2192)
			)
			(stroke
				(width 0)
				(type default)
			)
			(fill no)
			(layer "F.CrtYd")
		)
		(fp_rect
			(start -1.7018 1.2192)
			(end 1.7018 -1.2192)
			(stroke
				(width 0)
				(type default)
			)
			(fill no)
			(layer "F.Fab")
		)
		(pad "1" smd rect
			(at -0.73025 0.4064)
			(size 0.9144 0.6096)
			(layers "F.Cu" "F.Mask" "F.Paste")
			(net "SSD_ACT_DR4_MOS_N")
		)
		(pad "2" smd rect
			(at -0.73025 -0.4064)
			(size 0.9144 0.6096)
			(layers "F.Cu" "F.Mask" "F.Paste")
			(net "ATTN_LED_DR4_MOS_N")
		)
		(pad "3" smd rect
			(at 0.73025 -0.4064)
			(size 0.9144 0.6096)
			(layers "F.Cu" "F.Mask" "F.Paste")
			(net "DRV_ATTN_4")
		)
		(pad "4" smd rect
			(at 0.73025 0.4064)
			(size 0.9144 0.6096)
			(layers "F.Cu" "F.Mask" "F.Paste")
			(net "DRV_ACT_4")
		)
	)
	(footprint ""
		(layer "F.Cu")
		(at 47.879 -348.742 -90)
		(property "Reference" "R9898"
			(at 0 0 270)
			(layer "F.SilkS")
			(hide yes)
			(effects
				(font
					(size 1.27 1.27)
				)
			)
		)
		(property "Value" "1K82R2F-1-GP"
			(at 0.064008 -3.993896 270)
			(unlocked yes)
			(layer "F.Fab")
			(hide yes)
			(effects
				(font
					(size 1.016 1.016)
					(thickness 0.1524)
				)
			)
		)
		(property "Device Type" "R402H16"
			(at 0.064008 -5.517896 270)
			(unlocked yes)
			(layer "F.Fab")
			(hide yes)
			(effects
				(font
					(size 1.016 1.016)
					(thickness 0.1524)
				)
			)
		)
		(duplicate_pad_numbers_are_jumpers no)
		(fp_line
			(start -0.508 -0.9398)
			(end -0.508 0.9398)
			(stroke
				(width 0.1524)
				(type default)
			)
			(layer "F.SilkS")
		)
		(fp_line
			(start 0.508 -0.9398)
			(end -0.508 -0.9398)
			(stroke
				(width 0.1524)
				(type default)
			)
			(layer "F.SilkS")
		)
		(fp_rect
			(start -0.508 0.9398)
			(end 0.508 -0.9398)
			(stroke
				(width 0)
				(type default)
			)
			(fill no)
			(layer "F.CrtYd")
		)
		(fp_rect
			(start -0.508 0.9398)
			(end 0.508 -0.9398)
			(stroke
				(width 0)
				(type default)
			)
			(fill no)
			(layer "F.Fab")
		)
		(pad "1" smd custom
			(at 0 -0.4445 270)
			(size 0.1397 0.1397)
			(layers "F.Cu" "F.Mask" "F.Paste")
			(net "P12V")
			(options
				(clearance outline)
				(anchor circle)
			)
			(primitives
				(gr_poly
					(pts
						(arc
							(start -0.1778 -0.2794)
							(mid -0.249642 -0.249642)
							(end -0.2794 -0.1778)
						)
						(arc
							(start -0.2794 0.1778)
							(mid -0.249642 0.249642)
							(end -0.1778 0.2794)
						)
						(arc
							(start 0.1778 0.2794)
							(mid 0.249642 0.249642)
							(end 0.2794 0.1778)
						)
						(arc
							(start 0.2794 -0.1778)
							(mid 0.249642 -0.249642)
							(end 0.1778 -0.2794)
						)
					)
					(width 0)
					(fill yes)
				)
			)
		)
		(pad "2" smd custom
			(at 0 0.4445 270)
			(size 0.1397 0.1397)
			(layers "F.Cu" "F.Mask" "F.Paste")
			(net "DRV_ACT_6")
			(options
				(clearance outline)
				(anchor circle)
			)
			(primitives
				(gr_poly
					(pts
						(arc
							(start -0.1778 -0.2794)
							(mid -0.249642 -0.249642)
							(end -0.2794 -0.1778)
						)
						(arc
							(start -0.2794 0.1778)
							(mid -0.249642 0.249642)
							(end -0.1778 0.2794)
						)
						(arc
							(start 0.1778 0.2794)
							(mid 0.249642 0.249642)
							(end 0.2794 0.1778)
						)
						(arc
							(start 0.2794 -0.1778)
							(mid 0.249642 -0.249642)
							(end 0.1778 -0.2794)
						)
					)
					(width 0)
					(fill yes)
				)
			)
		)
	)
)
